(kicad_pcb
	(version 20260206)
	(generator "pcbnew")
	(generator_version "10.0")
	(general
		(thickness 1.6)
		(legacy_teardrops no)
	)
	(paper "A4")
	(title_block
		(title "12092022_DA0F0TYB4D0_F0T_Panel_BD_Front_D_brd_v02_OCP.brd")
		(comment 1 "Grand Teton / footprints 64-69 of 128")
	)
	(layers
		(0 "F.Cu" signal "TOP")
		(4 "In1.Cu" signal "GND")
		(6 "In2.Cu" signal "GND1")
		(2 "B.Cu" signal "BOTTOM")
		(9 "F.Adhes" user "F.Adhesive")
		(11 "B.Adhes" user "B.Adhesive")
		(13 "F.Paste" user "Package Geometry/Pastemask Top")
		(15 "B.Paste" user "Package Geometry/Pastemask Bottom")
		(5 "F.SilkS" user "Ref Des/Silkscreen Top")
		(7 "B.SilkS" user "Ref Des/Silkscreen Bottom")
		(1 "F.Mask" user "Board Geometry/Soldermask Top")
		(3 "B.Mask" user "Board Geometry/Soldermask Bottom")
		(17 "Dwgs.User" user "User.Drawings")
		(19 "Cmts.User" user "User.Comments")
		(21 "Eco1.User" user "User.Eco1")
		(23 "Eco2.User" user "User.Eco2")
		(25 "Edge.Cuts" user "Board Geometry/Outline")
		(27 "Margin" user)
		(31 "F.CrtYd" user "Package Geometry/Place Bound Top")
		(29 "B.CrtYd" user "Package Geometry/Place Bound Bottom")
		(35 "F.Fab" user "Ref Des/Assembly Top")
		(33 "B.Fab" user "Ref Des/Assembly Bottom")
	)
	(footprint ""
		(layer "F.Cu")
		(at 36.703 -19.304 180)
		(property "Reference" "R32"
			(at 2.032 -0.02667 0)
			(unlocked yes)
			(layer "F.SilkS")
			(effects
				(font
					(size 0.7874 0.5842)
					(thickness 0.1524)
				)
			)
		)
		(property "Value" ""
			(at 0 0 180)
			(layer "F.Fab")
			(effects
				(font
					(size 1.27 1.27)
				)
			)
		)
		(duplicate_pad_numbers_are_jumpers no)
		(fp_line
			(start 0.7874 0.4064)
			(end -0.7874 0.4064)
			(stroke
				(width 0.1524)
				(type default)
			)
			(layer "F.SilkS")
		)
		(fp_line
			(start 0.7874 -0.4064)
			(end 0.7874 0.4064)
			(stroke
				(width 0.1524)
				(type default)
			)
			(layer "F.SilkS")
		)
		(fp_line
			(start -0.7874 0.4064)
			(end -0.7874 -0.4064)
			(stroke
				(width 0.1524)
				(type default)
			)
			(layer "F.SilkS")
		)
		(fp_line
			(start -0.7874 -0.4064)
			(end 0.7874 -0.4064)
			(stroke
				(width 0.1524)
				(type default)
			)
			(layer "F.SilkS")
		)
		(fp_line
			(start 0.67945 0.3048)
			(end 0.120396 0.3048)
			(stroke
				(width 0.1)
				(type default)
			)
			(layer "F.Fab")
		)
		(fp_line
			(start 0.67945 -0.3048)
			(end 0.67945 0.3048)
			(stroke
				(width 0.1)
				(type default)
			)
			(layer "F.Fab")
		)
		(fp_line
			(start 0.12065 -0.2794)
			(end 0.12065 -0.3048)
			(stroke
				(width 0.1)
				(type default)
			)
			(layer "F.Fab")
		)
		(fp_line
			(start 0.12065 -0.3048)
			(end 0.67945 -0.3048)
			(stroke
				(width 0.1)
				(type default)
			)
			(layer "F.Fab")
		)
		(fp_line
			(start 0.120396 0.3048)
			(end 0.120396 0.2794)
			(stroke
				(width 0.1)
				(type default)
			)
			(layer "F.Fab")
		)
		(fp_line
			(start 0.120396 0.2794)
			(end -0.12065 0.2794)
			(stroke
				(width 0.1)
				(type default)
			)
			(layer "F.Fab")
		)
		(fp_line
			(start -0.12065 0.3048)
			(end -0.67945 0.3048)
			(stroke
				(width 0.1)
				(type default)
			)
			(layer "F.Fab")
		)
		(fp_line
			(start -0.12065 0.2794)
			(end -0.12065 0.3048)
			(stroke
				(width 0.1)
				(type default)
			)
			(layer "F.Fab")
		)
		(fp_line
			(start -0.12065 -0.2794)
			(end 0.12065 -0.2794)
			(stroke
				(width 0.1)
				(type default)
			)
			(layer "F.Fab")
		)
		(fp_line
			(start -0.12065 -0.305054)
			(end -0.12065 -0.2794)
			(stroke
				(width 0.1)
				(type default)
			)
			(layer "F.Fab")
		)
		(fp_line
			(start -0.67945 0.3048)
			(end -0.67945 -0.305054)
			(stroke
				(width 0.1)
				(type default)
			)
			(layer "F.Fab")
		)
		(fp_line
			(start -0.67945 -0.305054)
			(end -0.12065 -0.305054)
			(stroke
				(width 0.1)
				(type default)
			)
			(layer "F.Fab")
		)
		(pad "1" smd circle
			(at -0.40005 0 180)
			(size 0 0)
			(layers "F.Cu" "F.Mask" "F.Paste")
			(net "P3V3_STBY")
		)
		(pad "2" smd circle
			(at 0.40005 0 180)
			(size 0 0)
			(layers "F.Cu" "F.Mask" "F.Paste")
			(net "THERMAL_ADDR_A0")
		)
	)
	(footprint ""
		(layer "F.Cu")
		(at 19.67992 -6.679946)
		(property "Reference" "D1"
			(at -7.48792 -0.659384 0)
			(unlocked yes)
			(layer "F.SilkS")
			(effects
				(font
					(size 0.7874 0.5842)
					(thickness 0.1524)
				)
				(justify left)
			)
		)
		(property "Value" ""
			(at 0 0 0)
			(layer "F.Fab")
			(effects
				(font
					(size 1.27 1.27)
				)
			)
		)
		(duplicate_pad_numbers_are_jumpers no)
		(fp_line
			(start -6.04012 -1.27)
			(end 0.96012 -1.27)
			(stroke
				(width 0.1524)
				(type default)
			)
			(layer "F.SilkS")
		)
		(fp_line
			(start -6.04012 5.08)
			(end -6.04012 -1.27)
			(stroke
				(width 0.1524)
				(type default)
			)
			(layer "F.SilkS")
		)
		(fp_line
			(start -4.089908 5.08)
			(end -6.04012 5.08)
			(stroke
				(width 0.1524)
				(type default)
			)
			(layer "F.SilkS")
		)
		(fp_line
			(start -4.089908 6.230112)
			(end -4.089908 5.08)
			(stroke
				(width 0.1524)
				(type default)
			)
			(layer "F.SilkS")
		)
		(fp_line
			(start -0.990092 5.08)
			(end -0.990092 6.230112)
			(stroke
				(width 0.1524)
				(type default)
			)
			(layer "F.SilkS")
		)
		(fp_line
			(start 0.96012 -1.27)
			(end 0.96012 5.08)
			(stroke
				(width 0.1524)
				(type default)
			)
			(layer "F.SilkS")
		)
		(fp_line
			(start 0.96012 5.08)
			(end -0.990092 5.08)
			(stroke
				(width 0.1524)
				(type default)
			)
			(layer "F.SilkS")
		)
		(fp_arc
			(start -2.54 7.78002)
			(mid -3.63595 7.326062)
			(end -4.089908 6.230112)
			(stroke
				(width 0.1524)
				(type default)
			)
			(layer "F.SilkS")
		)
		(fp_arc
			(start -0.990092 6.230112)
			(mid -1.44405 7.326062)
			(end -2.54 7.78002)
			(stroke
				(width 0.1524)
				(type default)
			)
			(layer "F.SilkS")
		)
		(fp_line
			(start -6.04012 -1.27)
			(end 0.96012 -1.27)
			(stroke
				(width 0.1)
				(type default)
			)
			(layer "F.Fab")
		)
		(fp_line
			(start -6.04012 5.08)
			(end -6.04012 -1.27)
			(stroke
				(width 0.1)
				(type default)
			)
			(layer "F.Fab")
		)
		(fp_line
			(start -4.089908 5.08)
			(end -6.04012 5.08)
			(stroke
				(width 0.1)
				(type default)
			)
			(layer "F.Fab")
		)
		(fp_line
			(start -4.089908 6.230112)
			(end -4.089908 5.08)
			(stroke
				(width 0.1)
				(type default)
			)
			(layer "F.Fab")
		)
		(fp_line
			(start -0.990092 5.08)
			(end -0.990092 6.230112)
			(stroke
				(width 0.1)
				(type default)
			)
			(layer "F.Fab")
		)
		(fp_line
			(start 0.96012 -1.27)
			(end 0.96012 5.08)
			(stroke
				(width 0.1)
				(type default)
			)
			(layer "F.Fab")
		)
		(fp_line
			(start 0.96012 5.08)
			(end -0.990092 5.08)
			(stroke
				(width 0.1)
				(type default)
			)
			(layer "F.Fab")
		)
		(fp_arc
			(start -2.54 7.78002)
			(mid -3.63595 7.326062)
			(end -4.089908 6.230112)
			(stroke
				(width 0.1)
				(type default)
			)
			(layer "F.Fab")
		)
		(fp_arc
			(start -0.990092 6.230112)
			(mid -1.44405 7.326062)
			(end -2.54 7.78002)
			(stroke
				(width 0.1)
				(type default)
			)
			(layer "F.Fab")
		)
		(pad "1" thru_hole rect
			(at 0 0)
			(size 1.3716 1.3716)
			(drill 0.9652)
			(layers "*.Cu" "*.Mask")
			(remove_unused_layers no)
			(net "FM_PFR_LED_BLUE_R")
			(clearance 0.0508)
			(thermal_gap 0.0508)
			(padstack
				(mode front_inner_back)
				(layer "Inner"
					(shape circle)
					(size 1.3716 1.3716)
					(clearance 0.0508)
				)
				(layer "B.Cu"
					(shape rect)
					(size 1.3716 1.3716)
					(clearance 0.0508)
				)
			)
		)
		(pad "2" thru_hole circle
			(at -2.54 0)
			(size 1.3716 1.3716)
			(drill 0.9652)
			(layers "*.Cu" "*.Mask")
			(remove_unused_layers no)
			(net "GND")
			(clearance 0.0508)
			(thermal_gap 0.0508)
		)
		(pad "3" thru_hole circle
			(at -5.08 0)
			(size 1.3716 1.3716)
			(drill 0.9652)
			(layers "*.Cu" "*.Mask")
			(remove_unused_layers no)
			(net "FM_PFR_LED_AMBER_R")
			(clearance 0.0508)
			(thermal_gap 0.0508)
		)
	)
	(footprint ""
		(layer "F.Cu")
		(at 17.526 -23.114)
		(property "Reference" "R48"
			(at -0.127 -4.16433 0)
			(unlocked yes)
			(layer "F.SilkS")
			(effects
				(font
					(size 0.7874 0.5842)
					(thickness 0.1524)
				)
			)
		)
		(property "Value" ""
			(at 0 0 0)
			(layer "F.Fab")
			(effects
				(font
					(size 1.27 1.27)
				)
			)
		)
		(duplicate_pad_numbers_are_jumpers no)
		(fp_line
			(start -0.7874 -0.4064)
			(end 0.7874 -0.4064)
			(stroke
				(width 0.1524)
				(type default)
			)
			(layer "F.SilkS")
		)
		(fp_line
			(start -0.7874 0.4064)
			(end -0.7874 -0.4064)
			(stroke
				(width 0.1524)
				(type default)
			)
			(layer "F.SilkS")
		)
		(fp_line
			(start 0.7874 -0.4064)
			(end 0.7874 0.4064)
			(stroke
				(width 0.1524)
				(type default)
			)
			(layer "F.SilkS")
		)
		(fp_line
			(start 0.7874 0.4064)
			(end -0.7874 0.4064)
			(stroke
				(width 0.1524)
				(type default)
			)
			(layer "F.SilkS")
		)
		(fp_line
			(start -0.67945 -0.305054)
			(end -0.12065 -0.305054)
			(stroke
				(width 0.1)
				(type default)
			)
			(layer "F.Fab")
		)
		(fp_line
			(start -0.67945 0.3048)
			(end -0.67945 -0.305054)
			(stroke
				(width 0.1)
				(type default)
			)
			(layer "F.Fab")
		)
		(fp_line
			(start -0.12065 -0.305054)
			(end -0.12065 -0.2794)
			(stroke
				(width 0.1)
				(type default)
			)
			(layer "F.Fab")
		)
		(fp_line
			(start -0.12065 -0.2794)
			(end 0.12065 -0.2794)
			(stroke
				(width 0.1)
				(type default)
			)
			(layer "F.Fab")
		)
		(fp_line
			(start -0.12065 0.2794)
			(end -0.12065 0.3048)
			(stroke
				(width 0.1)
				(type default)
			)
			(layer "F.Fab")
		)
		(fp_line
			(start -0.12065 0.3048)
			(end -0.67945 0.3048)
			(stroke
				(width 0.1)
				(type default)
			)
			(layer "F.Fab")
		)
		(fp_line
			(start 0.120396 0.2794)
			(end -0.12065 0.2794)
			(stroke
				(width 0.1)
				(type default)
			)
			(layer "F.Fab")
		)
		(fp_line
			(start 0.120396 0.3048)
			(end 0.120396 0.2794)
			(stroke
				(width 0.1)
				(type default)
			)
			(layer "F.Fab")
		)
		(fp_line
			(start 0.12065 -0.3048)
			(end 0.67945 -0.3048)
			(stroke
				(width 0.1)
				(type default)
			)
			(layer "F.Fab")
		)
		(fp_line
			(start 0.12065 -0.2794)
			(end 0.12065 -0.3048)
			(stroke
				(width 0.1)
				(type default)
			)
			(layer "F.Fab")
		)
		(fp_line
			(start 0.67945 -0.3048)
			(end 0.67945 0.3048)
			(stroke
				(width 0.1)
				(type default)
			)
			(layer "F.Fab")
		)
		(fp_line
			(start 0.67945 0.3048)
			(end 0.120396 0.3048)
			(stroke
				(width 0.1)
				(type default)
			)
			(layer "F.Fab")
		)
		(pad "1" smd circle
			(at -0.40005 0)
			(size 0 0)
			(layers "F.Cu" "F.Mask" "F.Paste")
			(net "SMB_IO_DEBUG_CARD_SCL")
		)
		(pad "2" smd circle
			(at 0.40005 0)
			(size 0 0)
			(layers "F.Cu" "F.Mask" "F.Paste")
			(net "SMB_SCL")
		)
	)
	(footprint ""
		(layer "F.Cu")
		(at 29.972 -71.247)
		(property "Reference" "ME5"
			(at 0 0 0)
			(layer "F.SilkS")
			(hide yes)
			(effects
				(font
					(size 1.27 1.27)
				)
			)
		)
		(property "Value" ""
			(at 0 0 0)
			(layer "F.Fab")
			(effects
				(font
					(size 1.27 1.27)
				)
			)
		)
		(duplicate_pad_numbers_are_jumpers no)
		(fp_line
			(start 0 -6.999986)
			(end 0 -5.475986)
			(stroke
				(width 0.1524)
				(type default)
			)
			(layer "F.SilkS")
		)
		(fp_line
			(start 0 -1.524)
			(end 0 0)
			(stroke
				(width 0.1524)
				(type default)
			)
			(layer "F.SilkS")
		)
		(fp_line
			(start 0 0)
			(end 1.524 0)
			(stroke
				(width 0.1524)
				(type default)
			)
			(layer "F.SilkS")
		)
		(fp_line
			(start 1.524 -6.999986)
			(end 0 -6.999986)
			(stroke
				(width 0.1524)
				(type default)
			)
			(layer "F.SilkS")
		)
		(fp_line
			(start 5.475986 -6.999986)
			(end 6.999986 -6.999986)
			(stroke
				(width 0.1524)
				(type default)
			)
			(layer "F.SilkS")
		)
		(fp_line
			(start 6.999986 -6.999986)
			(end 6.999986 -5.475986)
			(stroke
				(width 0.1524)
				(type default)
			)
			(layer "F.SilkS")
		)
		(fp_line
			(start 6.999986 -1.524)
			(end 6.999986 0)
			(stroke
				(width 0.1524)
				(type default)
			)
			(layer "F.SilkS")
		)
		(fp_line
			(start 6.999986 0)
			(end 5.475986 0)
			(stroke
				(width 0.1524)
				(type default)
			)
			(layer "F.SilkS")
		)
		(fp_text user "S/N"
			(at 0.843788 -3.065526 0)
			(unlocked yes)
			(layer "F.SilkS")
			(effects
				(font
					(size 1.905 1.4224)
					(thickness 0.1524)
				)
				(justify left)
			)
		)
	)
	(footprint ""
		(layer "F.Cu")
		(at 15.113 -14.986 -90)
		(property "Reference" "R2"
			(at -1.651 0.60833 90)
			(unlocked yes)
			(layer "F.SilkS")
			(effects
				(font
					(size 0.7874 0.5842)
					(thickness 0.1524)
				)
			)
		)
		(property "Value" ""
			(at 0 0 270)
			(layer "F.Fab")
			(effects
				(font
					(size 1.27 1.27)
				)
			)
		)
		(duplicate_pad_numbers_are_jumpers no)
		(fp_line
			(start -0.7874 0.4064)
			(end -0.7874 -0.4064)
			(stroke
				(width 0.1524)
				(type default)
			)
			(layer "F.SilkS")
		)
		(fp_line
			(start 0.7874 0.4064)
			(end -0.7874 0.4064)
			(stroke
				(width 0.1524)
				(type default)
			)
			(layer "F.SilkS")
		)
		(fp_line
			(start -0.7874 -0.4064)
			(end 0.7874 -0.4064)
			(stroke
				(width 0.1524)
				(type default)
			)
			(layer "F.SilkS")
		)
		(fp_line
			(start 0.7874 -0.4064)
			(end 0.7874 0.4064)
			(stroke
				(width 0.1524)
				(type default)
			)
			(layer "F.SilkS")
		)
		(fp_line
			(start -0.67945 0.3048)
			(end -0.67945 -0.305054)
			(stroke
				(width 0.1)
				(type default)
			)
			(layer "F.Fab")
		)
		(fp_line
			(start -0.12065 0.3048)
			(end -0.67945 0.3048)
			(stroke
				(width 0.1)
				(type default)
			)
			(layer "F.Fab")
		)
		(fp_line
			(start 0.120396 0.3048)
			(end 0.120396 0.2794)
			(stroke
				(width 0.1)
				(type default)
			)
			(layer "F.Fab")
		)
		(fp_line
			(start 0.67945 0.3048)
			(end 0.120396 0.3048)
			(stroke
				(width 0.1)
				(type default)
			)
			(layer "F.Fab")
		)
		(fp_line
			(start -0.12065 0.2794)
			(end -0.12065 0.3048)
			(stroke
				(width 0.1)
				(type default)
			)
			(layer "F.Fab")
		)
		(fp_line
			(start 0.120396 0.2794)
			(end -0.12065 0.2794)
			(stroke
				(width 0.1)
				(type default)
			)
			(layer "F.Fab")
		)
		(fp_line
			(start -0.12065 -0.2794)
			(end 0.12065 -0.2794)
			(stroke
				(width 0.1)
				(type default)
			)
			(layer "F.Fab")
		)
		(fp_line
			(start 0.12065 -0.2794)
			(end 0.12065 -0.3048)
			(stroke
				(width 0.1)
				(type default)
			)
			(layer "F.Fab")
		)
		(fp_line
			(start 0.12065 -0.3048)
			(end 0.67945 -0.3048)
			(stroke
				(width 0.1)
				(type default)
			)
			(layer "F.Fab")
		)
		(fp_line
			(start 0.67945 -0.3048)
			(end 0.67945 0.3048)
			(stroke
				(width 0.1)
				(type default)
			)
			(layer "F.Fab")
		)
		(fp_line
			(start -0.67945 -0.305054)
			(end -0.12065 -0.305054)
			(stroke
				(width 0.1)
				(type default)
			)
			(layer "F.Fab")
		)
		(fp_line
			(start -0.12065 -0.305054)
			(end -0.12065 -0.2794)
			(stroke
				(width 0.1)
				(type default)
			)
			(layer "F.Fab")
		)
		(pad "1" smd circle
			(at -0.40005 0 270)
			(size 0 0)
			(layers "F.Cu" "F.Mask" "F.Paste")
			(net "FM_PFR_LED_AMBER_N")
		)
		(pad "2" smd circle
			(at 0.40005 0 270)
			(size 0 0)
			(layers "F.Cu" "F.Mask" "F.Paste")
			(net "FM_PFR_LED_AMBER_R_N")
		)
	)
	(footprint ""
		(layer "F.Cu")
		(at 9.525 -29.083 180)
		(property "Reference" "R10"
			(at -0.254 2.13233 0)
			(unlocked yes)
			(layer "F.SilkS")
			(effects
				(font
					(size 0.7874 0.5842)
					(thickness 0.1524)
				)
			)
		)
		(property "Value" ""
			(at 0 0 180)
			(layer "F.Fab")
			(effects
				(font
					(size 1.27 1.27)
				)
			)
		)
		(duplicate_pad_numbers_are_jumpers no)
		(fp_line
			(start 0.7874 0.4064)
			(end -0.7874 0.4064)
			(stroke
				(width 0.1524)
				(type default)
			)
			(layer "F.SilkS")
		)
		(fp_line
			(start 0.7874 -0.4064)
			(end 0.7874 0.4064)
			(stroke
				(width 0.1524)
				(type default)
			)
			(layer "F.SilkS")
		)
		(fp_line
			(start -0.7874 0.4064)
			(end -0.7874 -0.4064)
			(stroke
				(width 0.1524)
				(type default)
			)
			(layer "F.SilkS")
		)
		(fp_line
			(start -0.7874 -0.4064)
			(end 0.7874 -0.4064)
			(stroke
				(width 0.1524)
				(type default)
			)
			(layer "F.SilkS")
		)
		(fp_line
			(start 0.67945 0.3048)
			(end 0.120396 0.3048)
			(stroke
				(width 0.1)
				(type default)
			)
			(layer "F.Fab")
		)
		(fp_line
			(start 0.67945 -0.3048)
			(end 0.67945 0.3048)
			(stroke
				(width 0.1)
				(type default)
			)
			(layer "F.Fab")
		)
		(fp_line
			(start 0.12065 -0.2794)
			(end 0.12065 -0.3048)
			(stroke
				(width 0.1)
				(type default)
			)
			(layer "F.Fab")
		)
		(fp_line
			(start 0.12065 -0.3048)
			(end 0.67945 -0.3048)
			(stroke
				(width 0.1)
				(type default)
			)
			(layer "F.Fab")
		)
		(fp_line
			(start 0.120396 0.3048)
			(end 0.120396 0.2794)
			(stroke
				(width 0.1)
				(type default)
			)
			(layer "F.Fab")
		)
		(fp_line
			(start 0.120396 0.2794)
			(end -0.12065 0.2794)
			(stroke
				(width 0.1)
				(type default)
			)
			(layer "F.Fab")
		)
		(fp_line
			(start -0.12065 0.3048)
			(end -0.67945 0.3048)
			(stroke
				(width 0.1)
				(type default)
			)
			(layer "F.Fab")
		)
		(fp_line
			(start -0.12065 0.2794)
			(end -0.12065 0.3048)
			(stroke
				(width 0.1)
				(type default)
			)
			(layer "F.Fab")
		)
		(fp_line
			(start -0.12065 -0.2794)
			(end 0.12065 -0.2794)
			(stroke
				(width 0.1)
				(type default)
			)
			(layer "F.Fab")
		)
		(fp_line
			(start -0.12065 -0.305054)
			(end -0.12065 -0.2794)
			(stroke
				(width 0.1)
				(type default)
			)
			(layer "F.Fab")
		)
		(fp_line
			(start -0.67945 0.3048)
			(end -0.67945 -0.305054)
			(stroke
				(width 0.1)
				(type default)
			)
			(layer "F.Fab")
		)
		(fp_line
			(start -0.67945 -0.305054)
			(end -0.12065 -0.305054)
			(stroke
				(width 0.1)
				(type default)
			)
			(layer "F.Fab")
		)
		(pad "1" smd circle
			(at -0.40005 0 180)
			(size 0 0)
			(layers "F.Cu" "F.Mask" "F.Paste")
			(net "P5V_STBY")
		)
		(pad "2" smd circle
			(at 0.40005 0 180)
			(size 0 0)
			(layers "F.Cu" "F.Mask" "F.Paste")
			(net "PWR_LED_R1_N")
		)
	)
)
